 
 
Open CloudServer  
JBOD specification  
V1.0 
Authors: 
Mark Shaw, Director of Hardware Engineering, Microsoft 
Martin Goldstein, Principal Systems Architect, Microsoft 


 
2    January 28, 2014 
 
1 Revision History 
 
Date Name Description 
1/28/2014  Version 1.0 
   
   
   
   
   
   
   
 
 
 
 
  



Open Compute Project  Open CloudServer JBOD specification 
http://opencompute.org    3 
 
© 2014 Microsoft Corporation. 
 
As of January 28, 2014, the following persons or entities have made this Specification available under 
the Open Web Foundation Final Specification Agreement (OWFa 1.0), which is available at 
http://www.openwebfoundation.org/legal/the-owf-1-0-agreements/owfa-1-0 Microsoft Corporation.  
You can review the signed copies of the Open Web Foundation Agreement Version 1.0 for this 
Specification at http://opencompute.org/licensing/, which may also include additional parties to those 
listed above. 
Your use of this Specification may be subject to other third party rights. THIS SPECIFICATION IS 
PROVIDED "AS IS." The contributors expressly disclaim any warranties (express, implied, or otherwise), 
including implied warranties of merchantability, noninfringement, fitness for a particular purpose, or title, 
related to the Specification. The entire risk as to implementing or otherwise using the Specification is 
assumed by the Specification implementer and user. IN NO EVENT WILL ANY PARTY BE LIABLE TO ANY 
OTHER PARTY FOR LOST PROFITS OR ANY FORM OF INDIRECT, SPECIAL, INCIDENTAL, OR 
CONSEQUENTIAL DAMAGES OF ANY CHARACTER FROM ANY CAUSES OF ACTION OF ANY KIND WITH 
RESPECT TO THIS SPECIFICATION OR ITS GOVERNING AGREEMENT, WHETHER BASED ON BREACH OF 
CONTRACT, TORT (INCLUDING NEGLIGENCE), OR OTHERWISE, AND WHETHER OR NOT THE OTHER 
PARTY HAS BEEN ADVISED OF THE POSSIBILITY OF SUCH DAMAGE. 
CONTRIBUTORS AND LICENSORS OF THIS SPECIFICATION MAY HAVE MENTIONED CERTAIN 
TECHNOLOGIES THAT ARE MERELY REFERENCED WITHIN THIS SPECIFICATION AND NOT LICENSED 
UNDER THE OWF CLA OR OWFa. THE FOLLOWING IS A LIST OF MERELY REFERENCED TECHNOLOGY: 
INTELLIGENT PLATFORM MANAGEMENT INTERFACE (IPMI), I2C TRADEMARK OF PHILLIPS 
SEMICONDUCTOR. IMPLEMENTATION OF THESE TECHNOLOGIES MAY BE SUBJECT TO THEIR OWN 
LEGAL TERMS.  



 
4    January 28, 2014 
 
2 Scope 
This document provides the technical specifications for the design of the 6G half-
width JBOD blade for the Open CloudServer system.  
3 Contents 
1 Revision History ......................................................................................................................... 2 
2 Scope ......................................................................................................................................... 4 
3 Contents .................................................................................................................................... 4 
4 Overview.................................................................................................................................... 5 
5 Introduction to the 6G JBOD Blade ........................................................................................... 5 
5.1 Front View .................................................................................................................... 6 
5.2 Rear View ..................................................................................................................... 7 
6 Blade Design .............................................................................................................................. 8 
6.1 Storage Solution Design ............................................................................................... 8 
6.2 Expander Board Design .............................................................................................. 10 
6.3 Storage HDD Backplane Board Design ....................................................................... 18 
6.4 Connectors Plating ..................................................................................................... 21 
7 Mechanicals and Blade Physical Specification ........................................................................ 21 
7.1 6G JBOD Blade 3D Drawings ....................................................................................... 21 
7.2 HDD Bracket ............................................................................................................... 22 
7.3 HDD Latch and Release Mechanism ........................................................................... 23 
8 Electrical Specifications ........................................................................................................... 24 
8.1 Input Voltage, Power, Current ................................................................................... 24 
8.2 Current Interrupt Protection and Power, Voltage, and Current Monitoring ............. 25 
9 Management Subsystem ......................................................................................................... 25 
9.1 In-Band Manageability ............................................................................................... 26 
9.2 Out-of-Band Manageability/Blade API ....................................................................... 26 
10 Device Support and Scaling ..................................................................................................... 27 
10.1 Device Support ........................................................................................................... 27 
10.2 Cascading .................................................................................................................... 28 
11 Appendix: Commonly Used Acronyms .................................................................................... 28 



Open Compute Project  Open CloudServer JBOD specification 
http://opencompute.org    5 
 
4 Overview 
This document describes the Open CloudServer system “just a bunch of disks” (JBOD) 
storage blade. The JBOD blade is a half-width form factor blade design supported in 
the chassis system. The design includes the metal tray parts, 6 Gigabit (6G) expander 
board, hard disk drive (HDD) board, and cables.  
The 6G JBOD blade is a cost-effective, dense storage solution built to scale and meet 
storage application requirements. Like the compute blade, the 6G JBOD blade is a 
modular blade designed to ease serviceability, reduce system downtime, and simplify 
system manageability. 
5 Introduction to the 6G JBOD Blade  
The 6G JBOD is a 1U (1 rack unit) half-width form factor storage blade that supports 
10 x 3.5” HDDs. The blade is designed so that it can be serviced independently from 
the chassis and the rack infrastructure, without the need to disconnect cables or 
change the state of any adjacent blades.  
The 6G JBOD blade includes two types of boards: a single serial-attached small 
computer system interface (SAS) expander board and two HDDs backplane boards.  
The SAS expander board provides the connection to the local 10 x HDDs and mates 
with the tray backplane board; this enables the power and data signals to the blade 
and outside of the blade. Leveraging blind-mate connectors, the SAS expander board 
mates to the tray backplane where the external SAS I/O ports are located; this 
configuration makes it possible for host nodes or other JBODs to connect to the 
expander board. 
Figure 1 shows a view of the 6G JBOD blade (reference design shown). 



 
6    January 28, 2014 
 
 
Figure 1. 6G JBOD blade overview 
5.1 Front View 
The fronts of all blades have a similar look and a similar feature set. Each blade is 
secured and released with a latching handle and turn screw. Electromagnetic 
interference (EMI) containment is achieved with shielding materials and sized 
openings on the front of the blade. Each blade has two LEDs located at the front 
bottom right of the blade; these LEDs indicate power and attention status. 
Figure 2 shows a front view of the 6G JBOD blade (reference design shown). 
 
Figure 2. Front view of 6G JBOD blade 
Between the shielding materials on the lip of the front of the blade, there is a label 
that helps identify the HDD location; this makes it easier to service and bring up the 
system. 
Figure 3 shows the front lip of the 6G JBOD blade (reference design shown). 


Open Compute Project  Open CloudServer JBOD specification 
http://opencompute.org    7 
 
 
Figure 3. Front lip view of 6G JBOD blade 
5.2 Rear View 
The rear of the 6G JBOD mates with the rest of the system infrastructure. There are 
five mating components on the rear side of the blade: two FCI Electronics AirMax 
VSe 3x6 connectors, two mechanical guide pins, and one AirMax power connector.  
The AirMax VSe 3x6 connectors carry all of the storage I/O, blade management, and 
ground signals (no blade power is carried through the AirMax VSe 3x6 connector). 
The AirMax power connector delivers the 12V power. The two mechanical guide pins 
enable blade blind-mating to the chassis infrastructure. The 6G JBOD blade tray lies 
within the 1U mechanical full-width tray, which has additional guide and stop pins 
that help align the blade.  
There is an optional BOM-loaded LED that is visible from the rear of the blade. This 
LED is connected to the general purpose input output (GPIO) LED pin on the 
expander, which provides additional debug and serviceability features. 
Figure 4 shows the rear view of 6G JBOD blade (reference design shown). 
 
Figure 4. Rear view of 6G JBOD blade 


 
8    January 28, 2014 
 
6 Blade Design 
The 6G JBOD blade is a simplified storage solution with minimal hardware 
components. It sits in the mechanical tray and attaches to the tray backplane board. 
The blade consists of a small number of components and boards that can be easily 
accessed and serviced once the blade is outside of the chassis.  
Figure 5 shows the component layout of the 6G JBOD blade mated with the tray 
backplane board. 
 
Figure 5. System component layout 
6.1 Storage Solution Design 
The 6G JBOD blade enables a complete storage solution within the system 
infrastructure. Figure 6 shows a solution-level block diagram.  


Open Compute Project  Open CloudServer JBOD specification 
http://opencompute.org    9 
 
 
Figure 6. System block diagram 
Figure 6 shows the tray backplane, the 6G JBOD expander board, the host blade 
(compute blade with a storage controller), and the management hardware console 
(chassis manager). 
Both the host and JBOD blades mate with the tray backplane, which acts as a mid-
plane joining the two types of blades with a single Molex iPass mini-SAS external 
cable. The tray backplane resides within the 1U full-width mechanical tray in the 
chassis, which can connect to either a compute blade or a 6G JBOD blade. Various 
blade combination types are supported within the system infrastructure; this makes it 
possible to optimize the rack-level configurations for the application. 
Within the 6G JBOD blade, the HDDs are connected to serial AT attachment (SATA) 
backplane boards that carry the SATA signals through cables to the expander board. 
There are two SATA backplane boards that allow eight HDDs to be connected to the 


 
10    January 28, 2014 
 
expander board by cables. Two additional drives are connected to the expander 
board by a SATA connector located on one of the edges. 
The compute blade is located at the other end of the cable. The compute blade 
includes options for installing various RAID-On-Chip (ROC) and Host-Bus Adapter 
(HBA) controllers, enabling various storage blade feature sets and functionality. An 
Rx/Tx re-driver is also located inside the MCS compute blade, which helps with signal 
integrity on the data path. 
The chassis manager, a localized management hardware console, makes out-of-band 
(OOB) JBOD blade management possible. Communication to the SAS expander is via 
a Universal Asynchronous Receiver/Transmitter (UART) interface to the chassis 
manager. More detail about the chassis manager and additional devices (such as the 
compute blade and tray backplane) can be found in the other Open CloudServer 
specifications. 
6.2 Expander Board Design 
The SAS expander board acts as the central hardware component, connecting the 
end-devices to the host node. The expander board is located at the rear of the 1U 
half-width mechanical blade. The board also distributes the power going to the 
HDDs and the signals going to LED panel.  
Figure 7 shows a view of the expander board (reference design shown). 
 
Figure 7. Expander board 


Open Compute Project  Open CloudServer JBOD specification 
http://opencompute.org    11 
 
Figure 8 shows a block diagram of the expander board.
 
Figure 8. Blade expander board block diagram 
The expander uses LSISAS2x20, a reduced packaged LSI 6G SAS expander controller. 
The controller carries the SAS data signals to the AirMax VSE 3x6 connectors that 
mate to the tray backplane board. The controller is simplified to meet the minimum 
feature requirements of the blade. Many of the GPIO and I2C pins are not connected. 
The system is managed through selected out-of-band and in-band functions. Details 
of the management subsystems are included in this document and in the Open 
CloudServer chassis management specification. 
6.2.1 Expander Board Connectors 
The 6G JBOD blade includes a variety of connectors for mating the blade to the tray 
and for connecting to HDDs, status indicators, and debug ports. 
6.2.1.1 AirMax Signal and Power Connectors 
The blade includes two types of FCI AirMax connectors: VSe connectors for the SAS 
I/O data signals and power connectors for the 12V power. Both types of connectors 
mate with the tray backplane. 
AirMax Signal Connectors 
Two 3x6 VSe connectors (FCI AirMax VSe family coplanar connectors) are used for 
signals only (not used for power). An example of a coplanar connector pair is shown 
in Figure 9. The connector layout is shown in Figure 10, with the expander board 
header on the left and the mating tray backplane receptacle on the right.  


 
12    January 28, 2014 
 
 
Figure 9. Blade signal connector, coplanar example 
 
Figure 10. AirMax VSE pin arrangement, with blade header on left and backplane receptacle on right 
Table 1 shows the bus type distribution for the two AirMax VSe 3x6 connectors. 
Table 2 and Table 3 list the connector pin definitions. 
Table 1. AirMax VSe 3x6 Connector Pin Definition 


Open Compute Project  Open CloudServer JBOD specification 
http://opencompute.org    13 
 
 
Table 2. AirMax VSe 3x6 (1) Connector Pin Definition 
  


 
14    January 28, 2014 
 
Table 3. AirMax VSe 3x6 (2) Connector Pin Definition 
 
AirMax Power Connector 
The power connector, which supplies 12V to the 6G JBOD blade, is in the FCI AirMax 
Power family. Figure 11 shows the connector layout, and Table 4 shows the pin 
definition.  
Note that this connector is also included in the compute blade. 
 
 
Figure 11. AirMax power receptacle pinout arrangement 
 


Open Compute Project  Open CloudServer JBOD specification 
http://opencompute.org    15 
 
Table 4. AirMax Power Receptacle Pin Definition 
Pin Signal name Capacity 
Position 1 12V return – first mate 18A 
Position 2 12V supply 18A 
Position 4 12V supply 18A 
Position 3 12V return 18A 
The maximum power capacity on the 6G JBOD blade with a single connector is 
345W, 12V x 2 x 18 A x 80% de-rating. Note that depending on the implementation, 
these maximums might be unachievable. 
6.2.1.2 Additional Connectors  
There are six primary connectors on the 6G JBOD expander board, including the two 
described in the previous section (AirMax signal and power connectors). Table 5 
provides further detail. 
Table 5. 6G JBOD Expander Board Connector List 
Assembly 
mounting 
Assembly 
attachment Connector description  Quantity Manufacturing 
part number 
Expander 
board Tray backplane Power header AirMax VS,  2x2 1 (FCI) 10028918-
001LF 
Expander 
board Tray backplane 
Signal connector—three pair, 54 
contact, 2mm spacing, 17mm 
pitch, six column 
2 (FCI) 10039851-
101LF 
Expander 
board Tray backplane  Guide pin receptacle—10.8mm 
right angle, 0° key 2 (FCI) 10037912-
101LF 
Expander 
board SAS/SATA cable 6G IPASS SFF-8087 Mini-SAS 
Vertical header 2 (Molex) 75784-
0147 
Expander 
board HDD SATA signal and power 29-pin 2 (Molex) 97945-
0001 
Expander 
board Power cable 8-pin power vertical connector 1 N/A 
The 29-pin SATA signal and power receptacle connector on the expander board 
provides connectivity to a single SATA HDD. There are two 29-pin SATA connectors 
that allow direct connection of HDDs to the expander board. The connector follows 



 
16    January 28, 2014 
 
SFF-8482 specification, enabling serial signals and power on different contacts within 
the same housing. 
Table 6 provides the pin signal description for this 29-pin receptacle connector. 
Table 6. 29-Pin Signal Connector Description 
Pin Signal 
S1 Ground 
S2 Transmit + 
S3 Transmit - 
S4 Ground 
S5 Receive - 
S6 Receive + 
S7 Ground 
S8 NC 
S9 NC 
S10 NC 
S11 NC 
S12 NC 
S13 NC 
S14 NC 
P1 3.3V/NC 
P2 3.3V/NC 
P3 3.3V/NC 
P4 Ground 
P5 Ground 
P6 Ground 
P7 5V 
P8 5V 
P9 5V 
P10 Ground 
P11 NC 
P12 Ground 
P13 12V 
P14 12V 
P15 12V 



Open Compute Project  Open CloudServer JBOD specification 
http://opencompute.org    17 
 
Two HDDs in the JBOD blade are powered directly through the 29-pin connector; the 
remaining eight HDDs are powered through the 8-pin power connector, which 
connects to an 8-wire cable powering two HDD backplane boards. 
Table 7 provides the pin description for the 8-pin vertical connector. 
Table 7. 8-Pin Power Connector Description 
Pin Signal 
1 12V 
2 Ground 
3 5V 
4 Ground 
5 12V 
6 Ground 
7 5V 
8 Ground 
6.2.2 Expander Board Component List 
Following is list of the additional hardware components on the JBOD expander 
board: 
 Flash Read-Only Memory (ROM) device 
Spansion S29JL064J 
Provides storage for the local expander firmware, configurations, and various 
initialization method settings. 
 Serial Electrically Erasable Programmable Read-Only Memory (EEPROM) 
STMicroelectronics (ST) SG24C02 
Provides storage for device initialization information. 
 In-rush controller 
Analog Devices ADM1276 
Provides in-rush current control through the 12V bus rail. More information about 
in-rush power control signal can be found in the compute blade specification. 
 Temperature Sensor 
Texas Instruments (TI) TMP75 
Enables temperature monitoring. Temperature “High/Low” warning and critical 
thresholds can be set through the expander. 



 
18    January 28, 2014 
 
6.3 Storage HDD Backplane Board Design 
The second type of board within the 6G JBOD blade is the storage HDD backplane 
board, a double-sided printed circuit board assembly (PCBA) that acts as a mid-plane 
between the 6G JBOD expander board and the HDDs. Cables are used to connect 
the expander and storage HDD backplane board; these cables are 3M SAS fan-out 
cables that have a SFF-8087 SASx4 internal header on one end, and standard SATA 
7-pin single port receptacles on the other end. A single board can support 2x HDDs 
on each side (up to 4x HDDs per board). There are two HDD backplane boards in 
each 6G JBOD blade, allowing up to 8x HDDs to be supported via the HDD 
backplane board. Additional 2x HDDs can be supported with direct connections to 
the expander board, as described in the previous section.  
Figure 12 and Figure 13 show views of the storage HDD backplane board (reference 
design shown). 
 
Figure 12. Storage HDD backplane board, side 1 
 
Figure 13. Storage HDD backplane board, side 2 
Table 9 provides detail to the connectors on the storage HDD backplane board. 


Open Compute Project  Open CloudServer JBOD specification 
http://opencompute.org    19 
 
Table 9. 6G JBOD Expander Board Connector List 
Assembly 
mounting 
Assembly 
attachment Connector description  Quantity Manufacturing part 
number 
HDD 
backplane 
SAS/SATA 
cable SATA signal 7-pin 4 (LOTES) ABA-SAT-054-
P56 
HDD 
backplane HDD SATA signal and power 22-pin 4 (Amphenol) SAS-F313-
020-1-TR 
HDD 
backplane Power cable 4-pin power connector 1 N/A 
Similar to the 29-pin SATA signal and power receptacle connector on the expander 
board, there is a 22-pin SATA signal and power receptacle connector on the HDD 
backplane board. This also provides connectivity to a single SATA HDD and follows 
SFF-8482 specification, enabling serial signals and power on different contacts within 
the same housing. 
Table 10 provides the pin signal description of the 22-pin receptacle connector on 
the HDD backplane board.  
Table 10. 22-Pin Signal Connector Description 
Pin Signal 
S1 Ground 
S2 Transmit + 
S3 Transmit - 
S4 Ground 
S5 Receive - 
S6 Receive + 
S7 Ground 
P1 3.3V/NC 
P2 3.3V/NC 
P3 3.3V/NC 
P4 Ground 
P5 Ground 
P6 Ground 
P7 5V 
P8 5V 



 
20    January 28, 2014 
 
Pin Signal 
P9 5V 
P10 Ground 
P11 NC 
P12 Ground 
P13 12V 
P14 12V 
P15 12V 
Table 11 provides the pin signal description of the 7-pin plug connector on the HDD 
backplane board. 
Table 11. 7-Pin Signal Connector Description 
Pin Signal 
S1 Ground 
S2 Transmit + 
S3 Transmit - 
S4 Ground 
S5 Receive - 
S6 Receive + 
S7 Ground 
Table 12 provides the pin description for the 4-pin power connector. 
Table 12. 4-Pin Power Connector Description 
Pin Signal 
1 12V 
2 Ground 
3 5V 
4 Ground 
 
 



Open Compute Project  Open CloudServer JBOD specification 
http://opencompute.org    21 
 
Table 13 provides detail of the connectors on the 3M SAS fan-out cable. 
Table 13. 3M Cable Connector List 
3M cable side Cable description  Quantity Manufacturing part 
number 
SATA end 7-pin female SATA connector 4 (Yi-Lian Industrial) 
6SAS07S-320B-D 
IPASS mini-SAS end Internal mini-SAS connector, 
SFF-8087 1 (3M) 
78-9101-1588-6 
6.4 Connectors Plating 
The 6G JBOD blade is supported in environments up to 40°C with 90 percent relative 
humidity (RH). It is recommended that all connectors are plated with an appropriate 
thickness of gold plating with nickel under-plating; reliability testing and plating 
thickness consistency measurements are also recommended. Note that the 6G JBOD 
blade consists of connectors that have 15u” – 30u” Au with under-plating of up to 
100u” Ni. 
7 Mechanicals and Blade Physical Specification 
The physical specifications for the 6G JBOD blade are detailed in the compute blade 
specification, including the dimensions of the space into which the blade is installed, 
the blade weight limits, a description of the guiding and latching features, and 
information about electromagnetic interference shielding. The sections that follow are 
a subset of the compute blade specification. 
7.1 6G JBOD Blade 3D Drawings 
Figure 14 shows views of the 6G JBOD blade. The drawing on the left is the bare-
bone mechanical JBOD blade with no components; the drawing on the right is a 
mechanical JBOD blade with the expander board, HDD backplane board, and cable 
clips for routing.   



 
22    January 28, 2014 
 
 
Figure 14. 6G JBOD blade 3D drawings 
7.2 HDD Bracket 
A single HDD bracket is required for each of the ten HDDs in the 6G JBOD blade. 
The HDD bracket makes it possible for 3.5” screw-mount HDDs to securely attach 
into the mechanical blade. The bracket must follow SFF-8300 specification 
requirements and meet alternative mounting locations in the SFF-8301 Rev.1.6 
specification. 
The HDD bracket must also include dampeners. The elasticity of the dampeners is 
determined based on HDD support; the recommendation is to test and support at 
minimum for near-line Enterprise 7200RPM SATA HDDs. 
 
 
 
 
 


Open Compute Project  Open CloudServer JBOD specification 
http://opencompute.org    23 
 
Figure 15 shows the HDD bracket (reference design shown). 
 
Figure 15. HDD bracket 
There are four large guide pins on the bracket that help with mating and securing 
the HDD with the blade sheet metal. The two side smaller pins are used in the HDD 
latching and releasing mechanism, which is described in the next section. 
7.3 HDD Latch and Release Mechanism 
Each of the 10x HDDs have separate latching and releasing mechanisms that allows 
the HDDs to be serviced and swapped quickly. There are two parts to the 
mechanism: the special HDD bracket (described in the previous section) and the 
plastic release lever.  
Figure 16 shows the two pins used in the latch-and-release mechanism (reference 
design shown). 
 
Figure 16. HDD bracket (2) 
The HDD brackets have two dedicated pins that work with the plastic release lever. 
When the plastic lever is pressed on the outside of the blade, it lets the smaller pins 


 
24    January 28, 2014 
 
move, allowing the HDD bracket to move away from the connectors and 
disconnecting the HDD from the blade. 
Figure 17 shows the plastic release lever and the side of the blade where the lever 
can be pressed to release the pin. 
 
Figure 17. Plastic release lever 
8 Electrical Specifications 
The following sections provide a subset of information for the 6G JBOD blade 
electrical specification; more detail for the blades, 6G JBOD blade, and compute 
blade can be found in the compute blade specification. 
8.1 Input Voltage, Power, Current 
Table 14 lists the nominal, maximum, and minimum values for the blade input 
voltage. The maximum and minimum voltages include the impact of connector 
temperature, age, noise/ripple, and dynamic loading.  


Open Compute Project  Open CloudServer JBOD specification 
http://opencompute.org    25 
 
Table 14. Blade Input Voltage 
Nominal voltage Maximum voltage Minimum voltage 
12.25V DC 12.95V DC 11.65V DC 
The maximum amount of power allowed per blade is defined during system power 
allocation. The number of blades in a chassis might be limited by the capacity of the 
AC power cord or by the cooling capacity of the deployment. Table 15 lists the input 
power allocation for a low-power blade. 
Table 15. Input Power Allocation 
 Nominal 
voltage 
System power allocation 
(in W) Maximum current (in A) 
Low-power blade 
(1x power 
connector) 
12.25VDC 300W 27.3A 
The blade provides in-rush current control through the 12V bus rail; return-side in-
rush control is not used. The in-rush current rises linearly from 0A to the load current 
over a 5 millisecond (ms) period. (Note that this time period must be no longer than 
200ms.)  
8.2 Current Interrupt Protection and Power, Voltage, and Current 
Monitoring 
The 6G JBOD blade provides a cost-effective way to measure and report blade 
voltage and current consumption, and to make instance reporting available to the 
system. The blade includes power consumption measurements at the in-rush 
controller, and provides a way to interrupt current flow within 1 microsecond (μs) of 
exceeding three times the maximum current load. 
9 Management Subsystem 
The JBOD blade enables both in-band and out-of-band management. Like the 
compute blade, the 6G JBOD blade has two LEDs and an optional BOM-load LED for 
debugging.  



 
26    January 28, 2014 
 
More detail about the management subsystem can be found in the compute blade 
specification. 
9.1 In-Band Manageability 
The in-band functionality is implemented within the LSI expander (LSISAS2x20). Full 
management capability with the expander is enabled via the storage enclosure 
processor (SEP) software, which provides the SCSI Enclosure Service (SES) that 
monitors status and enables control of the HDDs. Various other management 
functions are enabled by SES, including HDD status, temperature monitoring, and DC 
voltage monitoring. The in-band functionality is supported through LSI utilities and 
software; management functions are fully supported though the LSI manageability 
implementation. 
9.2 Out-of-Band Manageability/Blade API 
In addition to self-monitoring and in-band management, the 6G JBOD blade permits 
out-of-band management through the management hardware console known as the 
chassis manager.  The backplane communicates with the SAS expander through a 
UART interface.  
The SAS expander firmware supports VT100 console output to enable communication 
with the backplane. The expander firmware also monitors the byte stream received 
on the UART interface for Intelligent Platform Management Interface (IPMI) packets.  
The filtering for IPMI packets works as follows: 
1. The received bytes are monitored for 0xA020. 0xA0 is the start byte for the 
IPMI packet, and 0x20 is the baseboard management controller (BMC) 
responder address. In this case, the expander plays the role of the BMC. 
2. If 0xA020 is received, monitor for 0xA5 to signify the end of the IPMI packet. 
If 0xA5 is received, the packet is processed as an IPMI command. If 0xA5 is 
not received within 128 bytes, the whole byte stream is processed as a VT100 
console input. 
3. If 0xA020 is not received before the end of the packet or a carriage return, 
the byte stream is processed as a VT100 console input. 



Open Compute Project  Open CloudServer JBOD specification 
http://opencompute.org    27 
 
Following is the list of commands supported within the 6G JBOD blade:  
 Get Device ID 
 Get System GUID 
 Get Channel Authentication Capabilities 
 Read FRU Data 
 Write FRU Data 
 Get Disk Status 
 Get Disk Info 
 Get Chassis Status 
Through the backplane, the 6G JBOD blade also provides a basic command-line 
interface (CLI) through the VT100 console as an alternative for users to monitor, 
configure, or update the JBOD blade. Features and functionality are based on the 
default LSI CLI modules from the LSI Bobcat software development kit (SDK).  
Following is a subset of the list of functions supported: 
 Show version 
 Get/set SAS address 
 Show disk status 
 Show/clear all PHYS error count 
 Read EEPROM data 
 Update expander FW 
 Reset expander 
10 Device Support and Scaling 
The sections that follow provide information about device support and scaling. 
10.1 Device Support 
The blade is intended to support single port storage devices only. The path from the 
expander to each SATA connector on the HDD board uses cable through one SAS 
path. At minimum, the 6G JBOD blade needs to support 6Gb/s near-line Enterprise 
7200RPM SATA HDDs. The current design does not support different HDD types 
within each JBOD blade. 



 
28    January 28, 2014 
 
10.2 Cascading 
It is possible to scale the storage capacity by daisy-chaining the 6G JBOD blades 
(cascading JBODs). Based on the selected LSI expander (LSISAS2x20), the expander 
table routing enables connections with as many as 1024 SAS addresses. It is 
recommended, however, that the maximum recommended cascading JBODs in series 
per x4 port is four layers; additional layers can result in increased latency and 
performance degradation to the application.  Capacity of a storage solution with four 
layers is eight JBODs and 80 HDDs. 
Figure 18 shows a storage topology with 4x 6G JBOD blades daisy-chained off of a 
single x4 port on the storage head node, compute blade. 
 
Figure 18. Cascading JBODs 
 
11 Appendix: Commonly Used Acronyms 
This section provides definitions of acronyms used in the system specifications. 


ACPI – advanced configuration and 
power interface  
AHCI – advanced host controller 
interface 
AHJ – authority having jurisdiction 
ANSI – American National 
Standards Institute 
API – application programming 
interface 
ASHRAE – American Society of 
Heating, Refrigerating and Air 
Conditioning Engineers 
ASIC – application-specific 
integrated circuit 
BCD – binary-coded decimal 
BIOS – basic input/output system 
BMC – baseboard management 
controller 
CFM – cubic feet per minute 
(measure of volume flow rate) 
CLI – command line interface 
CM – backplane 
CMOS – complementary metal–
oxide–semiconductor 
COLO – co-location 
CTS – clear to send 
DCMI – Data Center Manageability 
Interface 
DDR3 – double data rate type 3  
DHCP – dynamic host 
configuration protocol 
DIMM – dual inline memory 
module  
DPC - DIMMs per memory channel  
DRAM – dynamic random access 
memory 
DSR – data set ready 
DTR – data terminal ready 
ECC – error-correcting code 
EEPROM - electrically erasable 
programmable read-only memory 
EIA – Electronic Industries Alliance 
EMC – electromagnetic 
compatibility 
EMI – electromagnetic interference 
FRU – field replaceable unit 
FTP – file transfer protocol 
GPIO – general purpose input 
output 
GUID – globally unique identifier 
HBA – host-bus-adapter controller 
HBI – high business intelligence 
HCK – Windows Hardware 
Certification Kit 
HMD – hardware monitoring 
device 
HT – hyperthreading 
I2C – inter-integrated circuit 
IBC – international building code 
IDE – integrated development 
environment 
IEC - International Electrotechnical 
Commission 
IOC – I/O controller 
IPMI – intelligent platform 
management interface 
IPsec – IP security 



 
30    January 28, 2014 
 
ITPAC – IT pre-assembled 
components 
JBOD – “just a bunch of disks” 
KCS – keyboard controller style 
L2 – layer 2 
LAN – local area network 
LFF – large form factor 
LPC – low pin count 
LS – least significant 
LUN – logical unit number 
MAC – media access control 
MDC – modular data center 
containers 
MLC – multi-level call 
MTBF – mean time between 
failures  
MUX – multiplexer 
NIC – network interface card 
NUMA – non-uniform memory 
access 
OOB – out of band 
OSHA - Occupational Safety & 
Health Administration 
OTS – off the shelf 
PCB – printed circuit board 
PCIe – peripheral component 
interconnect express 
PCH – platform control hub 
PDB – power distribution 
backplane 
PDU – power distribution unit 
Ph-ph – phase to phase 
Ph-N – phase to neutral 
PNP – plug and play 
POST – power-on self-test 
PSU – power supply unit 
PWM – pulse-width modulation 
PXE – preboot execution 
environment 
QDR – quad data rate 
QFN – quad flat package no-lead 
QPI – Intel QuickPath Interconnect 
QSFP – Quad small form-factor 
pluggable 
RAID – redundant array of 
independent disks 
REST - representational state 
transfer 
RM – Rack Manager 
RMA – remote management agent 
ROC – RAID-on-chip controller 
RSS – receive-side scaling 
RTS – request to send 
RU – rack unit 
RxD – received data 
SAS – serial-attached small 
computer system interface (SCSI) 
SATA – serial AT attachment 
SCK – serial clock 
SCSI – small computer system 
interface 
SDA – serial data signal 



Open Compute Project  Open CloudServer JBOD specification 
http://opencompute.org    31 
 
SDR – sensor data record 
SEP – storage enclosure processor 
SES – SCSI enclosure service 
SFF – small form factor 
SFP – small form-factor pluggable  
SMBUS – systems management 
bus 
SMBIOS – systems management 
BIOS 
SOL – serial over LAN 
SPI – serial peripheral interface 
SSD – solid-state drive 
TB – tray backplane 
TDP – thermal design power 
TB – tray backplane 
TOR – top of rack 
TPM – trusted platform module 
TxD – transmit data 
U – rack unit 
UART – universal asynchronous 
receiver/transmitter 
UEFI – unified extensible firmware 
interface 
UL – Underwriters Laboratories 
UPS – uninterrupted power supply 
Vpp – voltage peak to peak 
WMI –Windows Management 
Interface 
 
 